G04*
G04 #@! TF.GenerationSoftware,Altium Limited,Altium Designer,22.4.2 (48)*
G04*
G04 Layer_Physical_Order=3*
G04 Layer_Color=65280*
%FSLAX25Y25*%
%MOIN*%
G70*
G04*
G04 #@! TF.SameCoordinates,446674BB-F454-490D-8607-5140536C8ADF*
G04*
G04*
G04 #@! TF.FilePolarity,Positive*
G04*
G01*
G75*
%ADD10C,0.01000*%
%ADD18C,0.00800*%
%ADD21C,0.00500*%
%ADD151C,0.03000*%
%ADD152C,0.02500*%
%ADD159C,0.07500*%
%ADD167C,0.01600*%
%ADD168C,0.03200*%
G36*
X577165Y-82284D02*
X391732D01*
Y-110236D01*
X340551D01*
Y-131890D01*
X324410D01*
Y-95669D01*
X371260D01*
Y-62598D01*
X577165D01*
Y-82284D01*
D02*
G37*
G36*
X602756Y-135433D02*
X588976D01*
Y-123622D01*
Y-123228D01*
X602756D01*
Y-135433D01*
D02*
G37*
G36*
X585039Y-211417D02*
X618110D01*
Y-235433D01*
X576545D01*
X576237Y-235306D01*
X575601D01*
X575293Y-235433D01*
X569685D01*
Y-210236D01*
X505512D01*
Y-191339D01*
X585039D01*
Y-211417D01*
D02*
G37*
G36*
X646063Y-254724D02*
X633071D01*
Y-243307D01*
X646063D01*
Y-254724D01*
D02*
G37*
%LPC*%
G36*
X528770Y-192797D02*
X528021D01*
X527329Y-193083D01*
X526799Y-193613D01*
X526512Y-194305D01*
Y-195054D01*
X526799Y-195746D01*
X527329Y-196276D01*
X528021Y-196563D01*
X528770D01*
X529462Y-196276D01*
X529992Y-195746D01*
X530278Y-195054D01*
Y-194305D01*
X529992Y-193613D01*
X529462Y-193083D01*
X528770Y-192797D01*
D02*
G37*
G36*
X531814Y-201992D02*
X531178D01*
X530590Y-202236D01*
X530140Y-202686D01*
X529896Y-203274D01*
Y-203910D01*
X530140Y-204499D01*
X530590Y-204948D01*
X531178Y-205192D01*
X531814D01*
X532402Y-204948D01*
X532853Y-204499D01*
X533096Y-203910D01*
Y-203274D01*
X532853Y-202686D01*
X532402Y-202236D01*
X531814Y-201992D01*
D02*
G37*
G36*
X525909D02*
X525272D01*
X524684Y-202236D01*
X524234Y-202686D01*
X523991Y-203274D01*
Y-203910D01*
X524234Y-204499D01*
X524684Y-204948D01*
X525272Y-205192D01*
X525909D01*
X526497Y-204948D01*
X526947Y-204499D01*
X527191Y-203910D01*
Y-203274D01*
X526947Y-202686D01*
X526497Y-202236D01*
X525909Y-201992D01*
D02*
G37*
G36*
X581273Y-205589D02*
X580636D01*
X580048Y-205833D01*
X579598Y-206283D01*
X579354Y-206871D01*
Y-207508D01*
X579598Y-208096D01*
X580048Y-208546D01*
X580636Y-208789D01*
X581273D01*
X581861Y-208546D01*
X582311Y-208096D01*
X582554Y-207508D01*
Y-206871D01*
X582311Y-206283D01*
X581861Y-205833D01*
X581273Y-205589D01*
D02*
G37*
%LPD*%
D10*
X78740Y-175197D02*
X86614D01*
X74803Y-179134D02*
X78740Y-175197D01*
D18*
X395669Y-164608D02*
G03*
X398598Y-171678I10000J0D01*
G01*
X398609Y-153359D02*
G03*
X398608Y-153360I3359J-3361D01*
G01*
X401968Y-151969D02*
G03*
X398609Y-153359I0J-4752D01*
G01*
X401968Y-151969D02*
G03*
X403150Y-149117I-2851J2851D01*
G01*
X392845Y-134971D02*
G03*
X385774Y-132042I-7071J-7071D01*
G01*
X377450D02*
G03*
X374016Y-133465I0J-4857D01*
G01*
X361606Y-141732D02*
G03*
X368677Y-138803I0J10000D01*
G01*
X332882Y-141732D02*
G03*
X325811Y-144661I0J-10000D01*
G01*
X322220Y-148252D02*
G03*
X319291Y-155323I7071J-7071D01*
G01*
X316362Y-237575D02*
G03*
X319291Y-230504I-7071J7071D01*
G01*
X306079Y-247859D02*
G03*
X303150Y-254929I7071J-7071D01*
G01*
Y-268692D02*
G03*
X306079Y-275764I10000J0D01*
G01*
X358566Y-278740D02*
G03*
X361417Y-277559I0J4033D01*
G01*
X370079Y-272047D02*
G03*
X364702Y-274274I0J-7604D01*
G01*
X387984Y-272047D02*
G03*
X395055Y-269118I0J10000D01*
G01*
X420284Y-248031D02*
G03*
X413213Y-250960I0J-10000D01*
G01*
X518110Y-251833D02*
G03*
X516535Y-248031I-5377J0D01*
G01*
X495858Y-301969D02*
G03*
X502929Y-299040I0J10000D01*
G01*
X161229Y-301969D02*
G03*
X154158Y-304897I0J-10000D01*
G01*
X297894Y-228740D02*
G03*
X311811Y-214823I0J13917D01*
G01*
X317717Y-117323D02*
G03*
X314380Y-113986I-3337J0D01*
G01*
X315748Y-136614D02*
G03*
X317717Y-134646I0J1969D01*
G01*
X314173Y-136614D02*
G03*
X311811Y-138976I0J-2362D01*
G01*
X311417Y-134646D02*
G03*
X314961Y-131102I0J3543D01*
G01*
X311417Y-134646D02*
G03*
X308661Y-137402I0J-2756D01*
G01*
X298661Y-225590D02*
G03*
X308661Y-215591I0J10000D01*
G01*
X312205Y-127017D02*
G03*
X309055Y-123868I-3150J0D01*
G01*
X311024Y-131102D02*
G03*
X312205Y-129921I0J1181D01*
G01*
X292599Y-131150D02*
G03*
X282677Y-141072I0J-9922D01*
G01*
Y-227165D02*
G03*
X286614Y-231102I3937J0D01*
G01*
X290709Y-128659D02*
G03*
X280709Y-138659I0J-10000D01*
G01*
Y-230315D02*
G03*
X283872Y-233478I3163J0D01*
G01*
X262425Y-244315D02*
G03*
X269496Y-247244I7071J7071D01*
G01*
X288189Y-247638D02*
G03*
X287239Y-247244I-950J-950D01*
G01*
X192126Y-169874D02*
G03*
X195055Y-176945I10000J0D01*
G01*
X193898Y-115009D02*
G03*
X192126Y-116781I0J-1772D01*
G01*
X262638Y-242166D02*
G03*
X269710Y-245095I7071J7071D01*
G01*
X193898Y-169283D02*
G03*
X196827Y-176354I10000J0D01*
G01*
X398598Y-171678D02*
X402264Y-175344D01*
X404823D01*
X395669Y-164608D02*
Y-156299D01*
X398608Y-153360D02*
X398609Y-153359D01*
X395669Y-156299D02*
X398608Y-153360D01*
X392845Y-134971D02*
X403150Y-145276D01*
X377450Y-132042D02*
X385774D01*
X368677Y-138803D02*
X374016Y-133465D01*
X332882Y-141732D02*
X361606D01*
X322220Y-148252D02*
X325811Y-144661D01*
X306079Y-247859D02*
X316362Y-237575D01*
X303150Y-268692D02*
Y-254929D01*
X309055Y-278740D02*
X358566D01*
X306079Y-275764D02*
X309055Y-278740D01*
X403150Y-149117D02*
Y-145276D01*
X319291Y-230504D02*
Y-155323D01*
X361417Y-277559D02*
X364702Y-274274D01*
X370079Y-272047D02*
X387984D01*
X395055Y-269118D02*
X413213Y-250960D01*
X420284Y-248031D02*
X516535D01*
X518110Y-283858D02*
Y-251833D01*
X502929Y-299040D02*
X518110Y-283858D01*
X161229Y-301969D02*
X495858D01*
X142520Y-316535D02*
X154158Y-304897D01*
X498376Y-279134D02*
X512402Y-265108D01*
X498376Y-275984D02*
X512402Y-261958D01*
X357135Y-288189D02*
X366191Y-279134D01*
X356742Y-286221D02*
X366978Y-275984D01*
X357923Y-292126D02*
X363188Y-286861D01*
X496259D01*
X512657Y-270462D01*
X366191Y-279134D02*
X498376D01*
X357529Y-290158D02*
X366024Y-281662D01*
X498946D02*
X512543Y-268065D01*
X366978Y-275984D02*
X498376D01*
X366024Y-281662D02*
X498946D01*
X105865Y-237409D02*
X158613Y-290158D01*
X357529D01*
X158219Y-292126D02*
X357923D01*
X159006Y-288189D02*
X357135D01*
X108465Y-235809D02*
X158876Y-286221D01*
X104528Y-238435D02*
X158219Y-292126D01*
X107165Y-236347D02*
X159006Y-288189D01*
X158876Y-286221D02*
X356742D01*
X326304Y-250984D02*
X354331D01*
X320095Y-244775D02*
X326304Y-250984D01*
X314658Y-244775D02*
X320095D01*
X434646Y-162598D02*
Y-156840D01*
Y-162598D02*
X440551Y-168504D01*
Y-177953D02*
Y-168504D01*
X418898Y-144143D02*
X421949D01*
X434646Y-156840D01*
X439370Y-179134D02*
X440551Y-177953D01*
X434282Y-179134D02*
X439370D01*
X416835Y-196581D02*
X434282Y-179134D01*
X416106Y-148783D02*
Y-144180D01*
Y-148783D02*
X423622Y-156299D01*
Y-167205D02*
Y-156299D01*
Y-167205D02*
X429001Y-172584D01*
Y-179660D02*
Y-172584D01*
X411811Y-196850D02*
X429001Y-179660D01*
X311811Y-214823D02*
Y-138976D01*
X288189Y-228740D02*
X297894D01*
X309016Y-113986D02*
X314380D01*
X317717Y-134646D02*
Y-117323D01*
X314173Y-136614D02*
X315748D01*
X308661Y-215591D02*
Y-137402D01*
X288583Y-225590D02*
X298661D01*
X314961Y-131102D02*
Y-118947D01*
X292599Y-131150D02*
Y-131102D01*
X311024D01*
X282677Y-227165D02*
Y-141072D01*
X286614Y-231102D02*
X288189D01*
X312205Y-129921D02*
Y-127017D01*
X290709Y-128659D02*
X309016D01*
X280709Y-230315D02*
Y-138659D01*
X283872Y-233478D02*
X288057D01*
X195055Y-176945D02*
X262425Y-244315D01*
X269496Y-247244D02*
X287239D01*
X192126Y-169874D02*
Y-116781D01*
X269710Y-245095D02*
X288057D01*
X196827Y-176354D02*
X262638Y-242166D01*
X193898Y-169283D02*
Y-119931D01*
X621063Y-51033D02*
X653543D01*
X451456Y-220640D02*
X621063Y-51033D01*
X653543D02*
X663386Y-41191D01*
X104528Y-238435D02*
Y-176972D01*
X26495Y-98940D02*
X104528Y-176972D01*
X364994Y-268586D02*
X414240Y-219340D01*
X360236Y-268586D02*
X364994D01*
X360236Y-272490D02*
X363189D01*
X415039Y-220640D01*
X26495Y-98940D02*
Y-8991D01*
X414240Y-219340D02*
X450917D01*
X415039Y-220640D02*
X451456D01*
X622177Y-48080D02*
X625000D01*
X450917Y-219340D02*
X622177Y-48080D01*
X663386Y-41191D02*
Y-26820D01*
X658465Y-21899D02*
X663386Y-26820D01*
X345669Y-203150D02*
X361417D01*
X337691Y-195171D02*
X345669Y-203150D01*
X326966Y-195171D02*
X337691D01*
X326969Y-197573D02*
X337731D01*
X347244Y-207087D02*
X361811D01*
X337731Y-197573D02*
X347244Y-207087D01*
X358661Y-194488D02*
X366535Y-202362D01*
X372047Y-163238D02*
X390202Y-145083D01*
X398568D01*
X372047Y-200756D02*
Y-163238D01*
X399508Y-136717D02*
Y-130265D01*
Y-136717D02*
X399618Y-136828D01*
X399606Y-136611D02*
X403792Y-140797D01*
X451048Y-217372D02*
X630772Y-37647D01*
X658465D01*
X39370Y-108138D02*
Y-9843D01*
Y-108138D02*
X107165Y-175932D01*
X39370Y-9843D02*
X40354Y-8858D01*
X416339Y-113435D02*
X460961D01*
X463551Y-116025D01*
X449754Y-176181D02*
X456250D01*
X457283Y-175147D01*
X445177Y-171604D02*
X449754Y-176181D01*
X461319Y-188336D02*
Y-143750D01*
X447915Y-201740D02*
X461319Y-188336D01*
X377921Y-203740D02*
X448671D01*
X464328Y-188083D01*
X354331Y-250984D02*
X375000Y-230315D01*
Y-192470D01*
X388976Y-178494D01*
X372016Y-200787D02*
X372047Y-200756D01*
X107165Y-236347D02*
Y-175932D01*
X105865Y-237409D02*
Y-176471D01*
X108465Y-235809D02*
Y-175394D01*
X379921Y-201740D02*
X447915D01*
X33465Y-104071D02*
X105865Y-176471D01*
X102394Y-211449D02*
X102528Y-211583D01*
X47244Y-114173D02*
X108465Y-175394D01*
X102394Y-211449D02*
Y-185088D01*
X95472Y-208661D02*
X101378Y-214567D01*
X95472Y-208661D02*
Y-185039D01*
X90551Y-180118D02*
X95472Y-185039D01*
X91660Y-219488D02*
X97125D01*
X82677Y-228471D02*
X91660Y-219488D01*
X82677Y-232283D02*
Y-228471D01*
X91535Y-216535D02*
X99410D01*
X86614Y-221457D02*
X91535Y-216535D01*
X86562Y-169257D02*
X102394Y-185088D01*
X80709Y-180118D02*
X90551D01*
X360236Y-262186D02*
X365619D01*
X365556Y-266186D02*
X414370Y-217372D01*
X360236Y-266186D02*
X365556D01*
X365587Y-264186D02*
X414054Y-215719D01*
X337756Y-272490D02*
X346060Y-264186D01*
X365587D01*
X423917Y-178494D02*
X427165Y-175246D01*
X47244Y-114173D02*
Y-8858D01*
X33465Y-104071D02*
Y-8858D01*
X413386Y-214419D02*
X450323D01*
X365619Y-262186D02*
X413386Y-214419D01*
X414054Y-215719D02*
X450862D01*
X414370Y-217372D02*
X451048D01*
X450862Y-215719D02*
X620079Y-46502D01*
Y-30364D01*
X618110Y-46632D02*
Y-28789D01*
X450323Y-214419D02*
X618110Y-46632D01*
X655118Y-26427D02*
X658465Y-29773D01*
X624016Y-26427D02*
X655118D01*
X620079Y-30364D02*
X624016Y-26427D01*
X446752Y-170029D02*
X450850Y-174127D01*
X464328Y-188083D02*
Y-146397D01*
X320866Y-272490D02*
X337756D01*
X618110Y-28789D02*
X625000Y-21899D01*
X403792Y-140797D02*
X432185D01*
X445177Y-171604D02*
Y-153789D01*
X446752Y-170029D02*
Y-152116D01*
X432185Y-140797D02*
X445177Y-153789D01*
X434133Y-139497D02*
X446752Y-152116D01*
X408398Y-139497D02*
X434133D01*
X405512Y-136611D02*
X408398Y-139497D01*
X399508Y-130265D02*
X416339Y-113435D01*
X426080Y-116043D02*
X456742D01*
X405512Y-136611D02*
X426080Y-116043D01*
X388976Y-178494D02*
X423917D01*
D21*
X453937Y-324867D02*
G03*
X453109Y-326866I1999J-1999D01*
G01*
X253871Y-353036D02*
G03*
X252457Y-356451I3415J-3415D01*
G01*
X440496Y-324924D02*
G03*
X440551Y-324852I-368J338D01*
G01*
X452009Y-326866D02*
G03*
X451181Y-324867I-2827J0D01*
G01*
X438623Y-326866D02*
G03*
X437795Y-324867I-2827J0D01*
G01*
X440496Y-324924D02*
G03*
X439907Y-326428I1611J-1499D01*
G01*
X262369Y-378512D02*
G03*
X263119Y-379262I750J0D01*
G01*
X263119Y-380762D02*
G03*
X263119Y-379262I0J750D01*
G01*
X261789Y-380762D02*
G03*
X261789Y-382262I0J-750D01*
G01*
X263077Y-383762D02*
G03*
X263077Y-382262I0J750D01*
G01*
X261970Y-383762D02*
G03*
X261221Y-384512I0J-750D01*
G01*
X262515Y-376738D02*
G03*
X262369Y-377091I354J-353D01*
G01*
X265092Y-374161D02*
G03*
X265557Y-373033I-1135J1128D01*
G01*
X263648Y-375606D02*
G03*
X263617Y-375679I446J-226D01*
G01*
X264312Y-373385D02*
G03*
X264457Y-373033I-355J352D01*
G01*
X262268Y-375487D02*
G03*
X262388Y-375355I-303J397D01*
G01*
X262268Y-375487D02*
G03*
X262139Y-375587I3362J-4466D01*
G01*
D02*
G03*
X260039Y-379958I3491J-4366D01*
G01*
X437962Y-335490D02*
G03*
X438623Y-333893I-1597J1597D01*
G01*
X438901Y-336106D02*
G03*
X439907Y-333679I-2428J2428D01*
G01*
X429620Y-340806D02*
G03*
X437460Y-337559I0J11087D01*
G01*
X257799Y-340806D02*
G03*
X250728Y-343735I0J-10000D01*
G01*
X242558Y-351905D02*
G03*
X239920Y-358273I6368J-6368D01*
G01*
X236673Y-366113D02*
G03*
X239920Y-358273I-7840J7840D01*
G01*
X234833Y-367953D02*
G03*
X231693Y-375524I7581J-7581D01*
G01*
X449862Y-338657D02*
G03*
X453109Y-330817I-7840J7840D01*
G01*
X438720Y-345206D02*
G03*
X446560Y-341959I0J11087D01*
G01*
X267399Y-345206D02*
G03*
X260328Y-348135I0J-10000D01*
G01*
X254657Y-353806D02*
G03*
X253557Y-356462I2656J-2656D01*
G01*
X250978Y-372280D02*
G03*
X253306Y-366660I-5620J5620D01*
G01*
X246410Y-376848D02*
G03*
X246264Y-377201I353J-353D01*
G01*
X246260Y-386706D02*
G03*
X246339Y-386975I500J-0D01*
G01*
X253431Y-363087D02*
G03*
X253306Y-363390I303J-303D01*
G01*
X449080Y-337883D02*
G03*
X452009Y-330812I-7071J7071D01*
G01*
X438715Y-344106D02*
G03*
X445786Y-341177I0J10000D01*
G01*
X267393Y-344106D02*
G03*
X259554Y-347354I0J-11087D01*
G01*
X248559Y-387253D02*
G03*
X248067Y-387647I-3J-500D01*
G01*
X245201Y-388468D02*
G03*
X248067Y-387647I1213J1180D01*
G01*
X242760Y-382451D02*
G03*
X245198Y-388465I8651J6D01*
G01*
X252457Y-362506D02*
G03*
X252206Y-363112I605J-605D01*
G01*
X246511Y-383395D02*
G03*
X246511Y-381894I0J750D01*
G01*
X245513Y-380395D02*
G03*
X246263Y-379645I0J750D01*
G01*
X244849Y-380395D02*
G03*
X244849Y-381894I0J-750D01*
G01*
X244848Y-383395D02*
G03*
X244848Y-384894I0J-750D01*
G01*
X246260Y-385645D02*
G03*
X245511Y-384894I-750J0D01*
G01*
X250197Y-371505D02*
G03*
X252206Y-366655I-4850J4850D01*
G01*
X245247Y-376455D02*
G03*
X242760Y-382451I5995J-6000D01*
G01*
X253431Y-363087D02*
G03*
X253557Y-362785I-303J303D01*
G01*
X267547Y-349419D02*
G03*
X267541Y-349426I8000J-7681D01*
G01*
X436269Y-350033D02*
G03*
X436268Y-350033I-1J-500D01*
G01*
X268693D02*
G03*
X268339Y-350183I3J-500D01*
G01*
X268339Y-350183D02*
G03*
X267969Y-350591I7218J-6921D01*
G01*
X436278Y-350033D02*
G03*
X460782Y-339880I-6J34663D01*
G01*
X267969Y-350591D02*
G03*
X265557Y-357104I7588J-6513D01*
G01*
X268692Y-348933D02*
G03*
X267555Y-349411I3J-1600D01*
G01*
X436273Y-348933D02*
G03*
X460008Y-339100I-6J33573D01*
G01*
X267541Y-349426D02*
G03*
X264457Y-357100I8007J-7675D01*
G01*
X260055Y-387716D02*
G03*
X263814Y-387648I1871J478D01*
G01*
X429615Y-339706D02*
G03*
X435659Y-337673I0J10000D01*
G01*
X264306Y-387253D02*
G03*
X263814Y-387648I-3J-500D01*
G01*
X435659Y-337673D02*
G03*
X436510Y-336930I-5012J6606D01*
G01*
X260039Y-387593D02*
G03*
X260055Y-387716I500J0D01*
G01*
X257793Y-339706D02*
G03*
X249954Y-342954I0J-11087D01*
G01*
X241770Y-351137D02*
G03*
X238820Y-358259I7121J-7121D01*
G01*
X235891Y-365339D02*
G03*
X238820Y-358268I-7071J7071D01*
G01*
X234046Y-367184D02*
G03*
X232307Y-369489I7360J-7360D01*
G01*
X232307Y-369489D02*
G03*
X230464Y-374724I8931J-6086D01*
G01*
X230464D02*
G03*
X230463Y-374763I499J-39D01*
G01*
X230404Y-382730D02*
G03*
X230250Y-383131I1544J-824D01*
G01*
X229180Y-385410D02*
G03*
X229573Y-385160I-41J498D01*
G01*
X231921Y-387253D02*
G03*
X231463Y-387326I0J-1480D01*
G01*
X229180Y-385410D02*
G03*
X231129Y-387687I151J-1844D01*
G01*
X231463Y-387326D02*
G03*
X231131Y-387679I153J-476D01*
G01*
X230404Y-382730D02*
G03*
X230463Y-382494I-441J236D01*
G01*
X229789Y-384818D02*
G03*
X229864Y-384653I-410J286D01*
G01*
X229789Y-384818D02*
G03*
X229573Y-385160I3743J-2610D01*
G01*
X233430Y-382804D02*
G03*
X233430Y-381304I0J750D01*
G01*
X231693Y-377554D02*
G03*
X232443Y-378304I750J-0D01*
G01*
X233066Y-379804D02*
G03*
X233066Y-378304I0J750D01*
G01*
X232213Y-379804D02*
G03*
X232213Y-381304I0J-750D01*
G01*
X231948Y-382804D02*
G03*
X231221Y-383370I0J-750D01*
G01*
X230556Y-385679D02*
G03*
X230699Y-385429I-6928J4128D01*
G01*
X229331Y-387253D02*
G03*
X230556Y-385679I-5703J5703D01*
G01*
X429124Y-321299D02*
G03*
X427953Y-324124I2828J-2828D01*
G01*
X253399Y-338606D02*
G03*
X246328Y-341535I0J-10000D01*
G01*
X253393Y-337506D02*
G03*
X245554Y-340754I0J-11087D01*
G01*
X230857Y-357006D02*
G03*
X227906Y-364131I7126J-7126D01*
G01*
X217253Y-388562D02*
G03*
X217903Y-386760I-1592J1592D01*
G01*
X436221Y-306757D02*
G03*
X435393Y-308755I1999J-1999D01*
G01*
X432145Y-318278D02*
G03*
X435393Y-310438I-7840J7840D01*
G01*
X425240Y-335079D02*
G03*
X427953Y-328529I-6549J6549D01*
G01*
X417117Y-338606D02*
G03*
X424962Y-335357I0J11093D01*
G01*
X214137Y-387647D02*
G03*
X213646Y-387253I-489J-106D01*
G01*
X214137Y-387647D02*
G03*
X217253Y-388562I1808J394D01*
G01*
X434293Y-308755D02*
G03*
X433465Y-306757I-2827J0D01*
G01*
X431364Y-317504D02*
G03*
X434293Y-310433I-7071J7071D01*
G01*
X428344Y-320523D02*
G03*
X426853Y-324125I3601J-3601D01*
G01*
X417114Y-337506D02*
G03*
X424186Y-334577I0J10000D01*
G01*
X230077Y-356230D02*
G03*
X226829Y-364073I7842J-7842D01*
G01*
X424457Y-334306D02*
G03*
X426853Y-328522I-5785J5785D01*
G01*
X223000Y-379138D02*
G03*
X224061Y-379138I530J530D01*
G01*
X223000Y-379138D02*
G03*
X221939Y-379138I-530J-530D01*
G01*
D02*
G03*
X221939Y-380199I530J-530D01*
G01*
X221939Y-381259D02*
G03*
X221939Y-380199I-530J530D01*
G01*
X220879Y-381259D02*
G03*
X221939Y-381259I530J530D01*
G01*
X220632Y-381013D02*
G03*
X219571Y-381013I-530J-530D01*
G01*
D02*
G03*
X219571Y-382073I530J-530D01*
G01*
X219818Y-383381D02*
G03*
X219818Y-382320I-530J530D01*
G01*
X218428Y-383051D02*
G03*
X217367Y-383051I-530J-530D01*
G01*
X218757Y-383381D02*
G03*
X219818Y-383381I530J530D01*
G01*
X217367Y-383051D02*
G03*
X217367Y-384112I530J-530D01*
G01*
X217696Y-385502D02*
G03*
X217696Y-384441I-530J530D01*
G01*
X261221Y-386262D02*
G03*
X261367Y-386616I500J0D01*
G01*
X450221Y-314836D02*
G03*
X457292Y-317765I7071J7071D01*
G01*
X465157Y-324873D02*
G03*
X462788Y-319156I-8086J0D01*
G01*
X462773Y-319140D02*
G03*
X459454Y-317765I-3320J-3320D01*
G01*
X448032Y-306757D02*
G03*
X447204Y-308755I1999J-1999D01*
G01*
X447203Y-310285D02*
G03*
X448288Y-312904I3704J0D01*
G01*
X461907Y-338755D02*
G03*
X465157Y-330911I-7844J7844D01*
G01*
X446103Y-310291D02*
G03*
X447507Y-313678I4791J0D01*
G01*
X449445Y-315617D02*
G03*
X457288Y-318865I7842J7842D01*
G01*
X446103Y-308755D02*
G03*
X445276Y-306757I-2827J0D01*
G01*
X464057Y-324890D02*
G03*
X461999Y-319922I-7026J0D01*
G01*
D02*
G03*
X459449Y-318865I-2550J-2550D01*
G01*
X461128Y-337980D02*
G03*
X464057Y-330908I-7071J7071D01*
G01*
X452009Y-330812D02*
Y-326866D01*
X246264Y-377201D02*
X246264Y-377201D01*
X438623Y-333893D02*
Y-326866D01*
X437795Y-324867D02*
Y-324852D01*
X439907Y-326428D02*
X439907Y-333679D01*
X453109Y-330817D02*
Y-326866D01*
X253871Y-353036D02*
X259554Y-347354D01*
X451181Y-324867D02*
Y-324852D01*
X440551Y-324852D02*
Y-324852D01*
X453937Y-324867D02*
Y-324852D01*
X262369Y-378512D02*
Y-377362D01*
X263119Y-379262D02*
X263119D01*
X261789Y-380762D02*
X263119D01*
X261789Y-382262D02*
X263077D01*
X261970Y-383762D02*
X263077D01*
X261221Y-386013D02*
Y-384512D01*
Y-386013D02*
X261221Y-386262D01*
X262515Y-376738D02*
X265092Y-374161D01*
X265557Y-373033D02*
Y-357104D01*
X264457Y-373033D02*
Y-357100D01*
X262369Y-377362D02*
Y-377091D01*
X263617Y-375679D02*
X263617D01*
X263648Y-375606D02*
X263648Y-375604D01*
X262468Y-375229D02*
X264312Y-373385D01*
X262388Y-375355D02*
X262468Y-375229D01*
X260039Y-387593D02*
Y-379958D01*
X227906Y-376757D02*
Y-364916D01*
X226829Y-376370D02*
Y-364916D01*
X226441Y-376757D02*
X226829Y-376370D01*
X227906Y-364916D02*
Y-364131D01*
X226829Y-364916D02*
Y-364073D01*
X225816Y-377383D02*
X226441Y-376757D01*
X437460Y-337559D02*
Y-337548D01*
X438901Y-336106D01*
X257799Y-340806D02*
X429620D01*
X242558Y-351905D02*
X250728Y-343735D01*
X234833Y-367953D02*
X236673Y-366113D01*
X234833Y-367953D02*
X234833Y-367953D01*
X231693Y-376230D02*
X231693Y-375524D01*
X446560Y-341959D02*
X449862Y-338657D01*
X267399Y-345206D02*
X438720D01*
X254657Y-353806D02*
X260328Y-348135D01*
X253557Y-362785D02*
Y-356462D01*
X246410Y-376848D02*
X250978Y-372280D01*
X246339Y-386975D02*
X246339Y-386975D01*
X246260Y-386706D02*
X246260D01*
X253306Y-366660D02*
Y-363390D01*
X445786Y-341177D02*
X449080Y-337883D01*
X267393Y-344106D02*
X438715D01*
X252457Y-362506D02*
Y-356451D01*
X248559Y-387253D02*
X249410D01*
X245198Y-388465D02*
X245201Y-388468D01*
X252206Y-366655D02*
Y-363112D01*
X246264Y-377451D02*
X246264Y-377201D01*
X246263Y-379645D02*
X246264Y-377451D01*
X246263Y-379645D02*
X246263D01*
X244849Y-381894D02*
X246511D01*
X246260Y-386020D02*
X246260Y-385645D01*
X244848Y-383395D02*
X246511D01*
X244849Y-380395D02*
X245513D01*
X246260Y-385645D02*
X246260D01*
X244848Y-384894D02*
X245511D01*
X246260Y-386270D02*
X246260Y-386020D01*
X246260Y-386706D02*
X246260Y-386270D01*
X245247Y-376455D02*
X250197Y-371505D01*
X436269Y-350033D02*
X436278D01*
X268339Y-350183D02*
X268339Y-350183D01*
X268693Y-350033D02*
X436268D01*
X268692Y-348933D02*
X436273Y-348933D01*
X267547Y-349419D02*
X267555Y-349411D01*
X263814Y-387648D02*
X263814Y-387648D01*
X257793Y-339706D02*
X429615D01*
X436510Y-336930D02*
X436521D01*
X241770Y-351137D02*
X249954Y-342954D01*
X238820Y-358268D02*
Y-358259D01*
X234046Y-367184D02*
X235891Y-365339D01*
X232307Y-369489D02*
Y-369489D01*
X230464Y-374724D02*
X230464D01*
X230463Y-382494D02*
X230463Y-374763D01*
X230249Y-383132D02*
X230250Y-383131D01*
X229864Y-384653D02*
X230249Y-383132D01*
X231921Y-387253D02*
X232480D01*
X229180Y-385410D02*
X229180Y-385410D01*
X231463Y-387326D02*
Y-387326D01*
X231129Y-387687D02*
X231131Y-387679D01*
X436521Y-336930D02*
X437962Y-335490D01*
X232443Y-378304D02*
X233066D01*
X232213Y-381304D02*
X233430D01*
X232213Y-379804D02*
X233066D01*
X231693Y-376230D02*
Y-376230D01*
X231693Y-376480D02*
X231693Y-376230D01*
X231693Y-377554D02*
X231693Y-376480D01*
X231948Y-382804D02*
X233430D01*
X231221Y-383370D02*
X231221D01*
X230699Y-385429D02*
X231221Y-383370D01*
X253399Y-338606D02*
X417117D01*
X429124Y-321299D02*
X429124Y-321299D01*
X253393Y-337506D02*
X417114D01*
X429124Y-321299D02*
X432145Y-318278D01*
X427953Y-328529D02*
Y-324124D01*
X230857Y-357006D02*
X246328Y-341535D01*
X230077Y-356230D02*
X245554Y-340754D01*
X217903Y-386760D02*
X227906Y-376757D01*
X436221Y-306757D02*
Y-306742D01*
X435393Y-310438D02*
Y-308755D01*
X424962Y-335357D02*
X425240Y-335079D01*
X213646Y-387253D02*
X213646D01*
X212795D02*
X213646D01*
X434293Y-310433D02*
Y-308755D01*
X433465Y-306757D02*
Y-306742D01*
X428344Y-320523D02*
X431364Y-317504D01*
X426853Y-328522D02*
Y-324125D01*
X424186Y-334577D02*
X424457Y-334306D01*
X224061Y-379138D02*
X225816Y-377383D01*
X223000Y-379138D02*
X223000Y-379138D01*
X223000Y-379138D02*
X223000Y-379138D01*
X221939Y-380199D02*
X221939Y-380199D01*
X220632Y-381013D02*
X220879Y-381259D01*
X219571Y-382073D02*
X219818Y-382320D01*
X218428Y-383051D02*
X218757Y-383381D01*
X217367Y-384112D02*
X217696Y-384441D01*
X217520Y-385679D02*
X217696Y-385502D01*
X215945Y-387253D02*
X217520Y-385679D01*
X457292Y-317765D02*
X459454D01*
X448288Y-312904D02*
X450221Y-314836D01*
X462773Y-319140D02*
X462788Y-319156D01*
X448032Y-306757D02*
Y-306742D01*
X447203Y-310285D02*
Y-308755D01*
X465157Y-330911D02*
Y-324873D01*
X460782Y-339880D02*
X461907Y-338755D01*
X264306Y-387253D02*
X265158D01*
X446103Y-310291D02*
Y-308755D01*
X457288Y-318865D02*
X459449D01*
X445276Y-306757D02*
Y-306742D01*
X464057Y-330908D02*
Y-324890D01*
X459449Y-318865D02*
Y-318865D01*
X261367Y-386616D02*
X262006Y-387255D01*
X447507Y-313678D02*
X449445Y-315617D01*
X460008Y-339100D02*
X461128Y-337980D01*
D151*
X600000Y-132283D02*
X616929D01*
X626772Y-122441D01*
X640945D01*
X660236Y-141732D01*
Y-199213D02*
Y-141732D01*
Y-199213D02*
X680315Y-219291D01*
Y-280709D02*
Y-219291D01*
X678740Y-280709D02*
X680315D01*
X666142Y-293307D02*
X678740Y-280709D01*
X666142Y-301575D02*
Y-293307D01*
X653150Y-314567D02*
X666142Y-301575D01*
X647244Y-308661D02*
X653150Y-314567D01*
X640158Y-308661D02*
X647244D01*
X634252Y-314567D02*
X640158Y-308661D01*
X600787Y-314567D02*
X634252D01*
X588976Y-302756D02*
X600787Y-314567D01*
X588583Y-303150D02*
X588976Y-302756D01*
X579528Y-303150D02*
X588583D01*
X547002Y-335675D02*
X579528Y-303150D01*
X508997Y-335675D02*
X547002D01*
X505118Y-339554D02*
X508997Y-335675D01*
X505118Y-346850D02*
Y-339554D01*
Y-346850D02*
X508903Y-350636D01*
X509391D01*
D152*
X601575Y-221260D02*
Y-200394D01*
X553543Y-152362D02*
X601575Y-200394D01*
X553543Y-152362D02*
Y-138189D01*
X575197Y-116535D01*
X599328D01*
X651557Y-64306D01*
D159*
X142520Y-316535D02*
D03*
D167*
X416835Y-196581D02*
D03*
X411811Y-196850D02*
D03*
X593307Y-127953D02*
D03*
X570866Y-70472D02*
D03*
Y-72441D02*
D03*
Y-74410D02*
D03*
X574016Y-70472D02*
D03*
Y-72441D02*
D03*
Y-74410D02*
D03*
X314658Y-244775D02*
D03*
X288583Y-225590D02*
D03*
X288189Y-228740D02*
D03*
Y-231102D02*
D03*
X288057Y-233478D02*
D03*
X288057Y-245095D02*
D03*
X288189Y-247638D02*
D03*
X588976Y-302756D02*
D03*
X579528Y-303150D02*
D03*
X330709Y-120473D02*
D03*
Y-123425D02*
D03*
Y-126378D02*
D03*
X593307Y-131102D02*
D03*
X595276D02*
D03*
X597244D02*
D03*
X595276Y-127953D02*
D03*
X597244D02*
D03*
X640945Y-250394D02*
D03*
Y-248425D02*
D03*
Y-246457D02*
D03*
X637795Y-250394D02*
D03*
Y-248425D02*
D03*
Y-246457D02*
D03*
X360236Y-268586D02*
D03*
Y-272490D02*
D03*
X625000Y-48080D02*
D03*
X658465Y-21899D02*
D03*
X26495Y-8991D02*
D03*
X512657Y-270462D02*
D03*
X544291Y-199655D02*
D03*
X509842Y-197687D02*
D03*
X544291Y-201624D02*
D03*
X509842Y-199655D02*
D03*
Y-201624D02*
D03*
X544291Y-197687D02*
D03*
X509842Y-195718D02*
D03*
X361811Y-207087D02*
D03*
X361417Y-203150D02*
D03*
X326969Y-197573D02*
D03*
X326966Y-195171D02*
D03*
X366535Y-202362D02*
D03*
X358661Y-194488D02*
D03*
X634252Y-314567D02*
D03*
X653150Y-314567D02*
D03*
X509391Y-350636D02*
D03*
X508997Y-335675D02*
D03*
X451181Y-324852D02*
D03*
X437795D02*
D03*
X453937D02*
D03*
X440551D02*
D03*
X399618Y-136828D02*
D03*
X377921Y-203740D02*
D03*
X372016Y-200787D02*
D03*
X379921Y-201740D02*
D03*
X102528Y-211583D02*
D03*
X97125Y-219488D02*
D03*
X99410Y-216535D02*
D03*
X101378Y-214567D02*
D03*
X86614Y-175197D02*
D03*
X360236Y-262186D02*
D03*
Y-266186D02*
D03*
X86614Y-221457D02*
D03*
X427165Y-175246D02*
D03*
X47244Y-8858D02*
D03*
X40354D02*
D03*
X33465D02*
D03*
X82677Y-232283D02*
D03*
X74803Y-179134D02*
D03*
X86562Y-169257D02*
D03*
X80709Y-180118D02*
D03*
X544291Y-195718D02*
D03*
X651557Y-64306D02*
D03*
X450850Y-174127D02*
D03*
X320866Y-272490D02*
D03*
X463551Y-116025D02*
D03*
X658465Y-37647D02*
D03*
Y-29773D02*
D03*
X625000Y-21899D02*
D03*
X314961Y-118947D02*
D03*
X309016Y-128659D02*
D03*
X418898Y-144143D02*
D03*
X405512Y-136611D02*
D03*
X416106Y-144180D02*
D03*
X398568Y-145083D02*
D03*
X246339Y-386975D02*
D03*
X249410Y-387253D02*
D03*
X232480D02*
D03*
X229331D02*
D03*
X436221Y-306742D02*
D03*
X212795Y-387253D02*
D03*
X433465Y-306742D02*
D03*
X215945Y-387253D02*
D03*
X262006Y-387255D02*
D03*
X448032Y-306742D02*
D03*
X265158Y-387253D02*
D03*
X445276Y-306742D02*
D03*
X456742Y-116043D02*
D03*
X464328Y-146397D02*
D03*
X461319Y-143750D02*
D03*
X457283Y-175147D02*
D03*
X512402Y-261958D02*
D03*
Y-265108D02*
D03*
X512543Y-268065D02*
D03*
X404823Y-175344D02*
D03*
X402264D02*
D03*
X309016Y-113986D02*
D03*
X193898Y-115009D02*
D03*
Y-119931D02*
D03*
X309055Y-123868D02*
D03*
D168*
X611417Y-227953D02*
D03*
Y-223228D02*
D03*
X604724Y-227953D02*
D03*
X598819Y-228346D02*
D03*
X604724Y-222835D02*
D03*
X599065Y-223031D02*
D03*
M02*
